(kicad_pcb
	(version 20221018)
	(generator pcbnew)
	(general
    (thickness 1.656)
  )
	(paper "A4")
	(title_block
    (title "SDI-MIPI Bridge")
    (date "2023-08-09")
    (rev "1.3.4")
    (company "Antmicro")
		(comment 9 "footprints 49-57 of 190")
	)
	(layers
    (0 "F.Cu" signal)
    (1 "In1.Cu" power)
    (2 "In2.Cu" power)
    (3 "In3.Cu" signal)
    (4 "In4.Cu" signal)
    (31 "B.Cu" signal)
    (32 "B.Adhes" user "B.Adhesive")
    (33 "F.Adhes" user "F.Adhesive")
    (34 "B.Paste" user)
    (35 "F.Paste" user)
    (36 "B.SilkS" user "B.Silkscreen")
    (37 "F.SilkS" user "F.Silkscreen")
    (38 "B.Mask" user)
    (39 "F.Mask" user)
    (40 "Dwgs.User" user "User.Drawings")
    (41 "Cmts.User" user "User.Comments")
    (42 "Eco1.User" user "User.Eco1")
    (43 "Eco2.User" user "User.Eco2")
    (44 "Edge.Cuts" user)
    (45 "Margin" user)
    (46 "B.CrtYd" user "B.Courtyard")
    (47 "F.CrtYd" user "F.Courtyard")
    (48 "B.Fab" user)
    (49 "F.Fab" user)
  )
	(footprint "sdi-mipi-bridge-footprints:C_0402_1005Metric" (layer "F.Cu")
    (at 109.9 124.6 -90)
    (descr "Capacitor SMD 0402")
    (tags "capacitor SMD 0402")
    (property "Author" "Antmicro")
    (property "Dielectric" "X7R")
    (property "License" "Apache-2.0")
    (property "MPN" "GRM155R71H103KA88D")
    (property "Manufacturer" "Murata")
    (property "Sheetfile" "sdi-mipi-bridge.kicad_sch")
    (property "Sheetname" "")
    (property "Val" "10n")
    (property "Voltage" "50V")
    (property "ki_description" " ")
    (attr smd)
    (fp_text reference "C65" (at 1.5 -0.4 90) (layer "F.SilkS")
        (effects (font (size 0.65 0.65) (thickness 0.15)) (justify right bottom))
    )
    (fp_text value "C_10n_0402" (at 0 1.4 90) (layer "F.Fab") hide
        (effects (font (size 0.7 0.7) (thickness 0.15)) (justify right bottom))
    )
    (fp_text user "Author: Antmicro" (at -0.932 4.17 90) (layer "F.Fab") hide
        (effects (font (size 0.7 0.7) (thickness 0.15)) (justify right bottom))
    )
    (fp_text user "${REFERENCE}" (at -0.932 3.168 90) (layer "F.Fab") hide
        (effects (font (size 0.7 0.7) (thickness 0.15)) (justify right bottom))
    )
    (fp_text user "License: Apache-2.0" (at -0.932 5.17 90) (layer "F.Fab") hide
        (effects (font (size 0.7 0.7) (thickness 0.15)) (justify right bottom))
    )
    (fp_rect (start -0.94 -0.47) (end 0.94 0.47)
      (stroke (width 0.05) (type solid)) (fill none) (layer "F.CrtYd"))
    (fp_rect (start -0.499 -0.249) (end 0.499 0.249)
      (stroke (width 0.15) (type solid)) (fill none) (layer "F.Fab"))
    (pad "1" smd roundrect (at -0.484 0 270) (size 0.59 0.64) (layers "F.Cu" "F.Paste" "F.Mask") (roundrect_rratio 0.25)
      (net 57 "VDD") (pintype "passive"))
    (pad "2" smd roundrect (at 0.484 0 270) (size 0.59 0.64) (layers "F.Cu" "F.Paste" "F.Mask") (roundrect_rratio 0.25)
      (net 3 "GNDA") (pintype "passive"))
  )
	(footprint "sdi-mipi-bridge-footprints:LED_0603_1608Metric_G" (layer "F.Cu")
    (at 133 104.4 90)
    (descr "LED SMD 0603 Green")
    (tags "LED SMD 0603 Green")
    (property "Author" "Antmicro")
    (property "License" "Apache-2.0")
    (property "MPN" "LG L29K-G2J1-24-Z")
    (property "Manufacturer" "Osram")
    (property "Sheetfile" "sdi-mipi-bridge.kicad_sch")
    (property "Sheetname" "")
    (attr smd)
    (fp_text reference "D5" (at 0.2 -0.7 90) (layer "F.SilkS")
        (effects (font (size 0.65 0.65) (thickness 0.15)) (justify left bottom))
    )
    (fp_text value "LED_G_0603_LG_L29K-G2J1-24-Z" (at 0 1.6 90) (layer "F.Fab") hide
        (effects (font (size 0.7 0.7) (thickness 0.15)) (justify left bottom))
    )
    (fp_text user "Author: Antmicro" (at -1.31 4.769 90) (layer "F.Fab") hide
        (effects (font (size 0.7 0.7) (thickness 0.15)) (justify left bottom))
    )
    (fp_text user "${REFERENCE}" (at -1.31 3.769 90) (layer "F.Fab") hide
        (effects (font (size 0.7 0.7) (thickness 0.15)) (justify left bottom))
    )
    (fp_text user "License: Apache-2.0" (at -1.31 5.769 90) (layer "F.Fab") hide
        (effects (font (size 0.7 0.7) (thickness 0.15)) (justify left bottom))
    )
    (fp_line (start -0.27 -0.35) (end 0.27 -0.35)
      (stroke (width 0.15) (type solid)) (layer "F.SilkS"))
    (fp_line (start -0.27 0.351) (end 0.27 0.351)
      (stroke (width 0.15) (type solid)) (layer "F.SilkS"))
    (fp_line (start -0.106328 -0.200008) (end -0.106328 0.199992)
      (stroke (width 0.1) (type solid)) (layer "F.SilkS"))
    (fp_line (start -0.106328 -0.200008) (end 0.093672 -0.000008)
      (stroke (width 0.1) (type solid)) (layer "F.SilkS"))
    (fp_line (start -0.106328 -0.000008) (end -0.29 0)
      (stroke (width 0.1) (type solid)) (layer "F.SilkS"))
    (fp_line (start 0.093672 -0.200008) (end 0.093672 0.199992)
      (stroke (width 0.1) (type solid)) (layer "F.SilkS"))
    (fp_line (start 0.093672 -0.000008) (end -0.106328 0.199992)
      (stroke (width 0.1) (type solid)) (layer "F.SilkS"))
    (fp_line (start 0.093672 -0.000008) (end 0.293672 -0.000008)
      (stroke (width 0.1) (type solid)) (layer "F.SilkS"))
    (fp_line (start 1.25 0.32) (end 1.25 -0.32)
      (stroke (width 0.15) (type solid)) (layer "F.SilkS"))
    (fp_rect (start 1.26 0.65) (end -1.26 -0.65)
      (stroke (width 0.05) (type solid)) (fill none) (layer "F.CrtYd"))
    (fp_line (start -0.599 0) (end -0.201 0)
      (stroke (width 0.15) (type solid)) (layer "F.Fab"))
    (fp_line (start -0.201 -0.2) (end -0.201 0)
      (stroke (width 0.15) (type solid)) (layer "F.Fab"))
    (fp_line (start -0.201 0) (end -0.201 0.202)
      (stroke (width 0.15) (type solid)) (layer "F.Fab"))
    (fp_line (start -0.201 0.202) (end 0.101 0)
      (stroke (width 0.15) (type solid)) (layer "F.Fab"))
    (fp_line (start 0.101 0) (end -0.201 -0.2)
      (stroke (width 0.15) (type solid)) (layer "F.Fab"))
    (fp_line (start 0.199 -0.2) (end 0.199 -0.1)
      (stroke (width 0.15) (type solid)) (layer "F.Fab"))
    (fp_line (start 0.199 0) (end 0.597 0)
      (stroke (width 0.15) (type solid)) (layer "F.Fab"))
    (fp_line (start 0.199 0.202) (end 0.199 -0.1)
      (stroke (width 0.15) (type solid)) (layer "F.Fab"))
    (fp_rect (start -0.848 -0.4) (end 0.85 0.402)
      (stroke (width 0.15) (type solid)) (fill none) (layer "F.Fab"))
    (pad "1" smd rect (at -0.75 0 270) (size 0.8 0.8) (layers "F.Cu" "F.Paste" "F.Mask")
      (net 95 "Net-(D5-Pad1)") (pintype "passive"))
    (pad "2" smd rect (at 0.75 0 270) (size 0.8 0.8) (layers "F.Cu" "F.Paste" "F.Mask")
      (net 1 "GNDREF") (pinfunction "2") (pintype "passive"))
  )
	(footprint "sdi-mipi-bridge-footprints:R_0402_1005Metric" (layer "F.Cu")
    (at 138 129.75 90)
    (descr "Resistor SMD 0402")
    (tags "resistor SMD 0402")
    (property "Author" "Antmicro")
    (property "License" "Apache-2.0")
    (property "MPN" "CR0402-FX-1002GLF")
    (property "Manufacturer" "Bourns")
    (property "Sheetfile" "sdi-mipi-bridge.kicad_sch")
    (property "Sheetname" "")
    (property "Tolerance" "1%")
    (property "Val" "10k")
    (property "ki_description" "10k resistor in 0402 package with 1% tolerance")
    (attr smd)
    (fp_text reference "R65" (at -5.75 0.4 90) (layer "F.SilkS")
        (effects (font (size 0.65 0.65) (thickness 0.15)) (justify left bottom))
    )
    (fp_text value "R_10k_0402" (at 0 1.4 90) (layer "F.Fab") hide
        (effects (font (size 0.7 0.7) (thickness 0.15)) (justify left bottom))
    )
    (fp_text user "${REFERENCE}" (at -0.95 3.168 90) (layer "F.Fab") hide
        (effects (font (size 0.7 0.7) (thickness 0.15)) (justify left bottom))
    )
    (fp_text user "Author: Antmicro" (at -0.95 4.169 90) (layer "F.Fab") hide
        (effects (font (size 0.7 0.7) (thickness 0.15)) (justify left bottom))
    )
    (fp_text user "License: Apache-2.0" (at -0.95 5.169 90) (layer "F.Fab") hide
        (effects (font (size 0.7 0.7) (thickness 0.15)) (justify left bottom))
    )
    (fp_rect (start -0.93 -0.47) (end 0.93 0.47)
      (stroke (width 0.05) (type solid)) (fill none) (layer "F.CrtYd"))
    (fp_rect (start -0.5 -0.25) (end 0.5 0.25)
      (stroke (width 0.15) (type solid)) (fill none) (layer "F.Fab"))
    (pad "1" smd roundrect (at -0.485 0 90) (size 0.59 0.64) (layers "F.Cu" "F.Paste" "F.Mask") (roundrect_rratio 0.25)
      (net 105 "/USER_SW") (pintype "passive"))
    (pad "2" smd roundrect (at 0.485 0 90) (size 0.59 0.64) (layers "F.Cu" "F.Paste" "F.Mask") (roundrect_rratio 0.25)
      (net 76 "IO_VDD") (pintype "passive"))
  )
	(footprint "sdi-mipi-bridge-footprints:R_0402_1005Metric" (layer "F.Cu")
    (at 138 131.765 90)
    (descr "Resistor SMD 0402")
    (tags "resistor SMD 0402")
    (property "Author" "Antmicro")
    (property "DNP" "DNP")
    (property "License" "Apache-2.0")
    (property "MPN" "CR0402-FX-1002GLF")
    (property "Manufacturer" "Bourns")
    (property "Sheetfile" "sdi-mipi-bridge.kicad_sch")
    (property "Sheetname" "")
    (property "Tolerance" "1%")
    (property "Val" "10k")
    (property "ki_description" "10k resistor in 0402 package with 1% tolerance")
    (attr exclude_from_pos_files)
    (fp_text reference "R66" (at -5.75 0.4 90) (layer "F.SilkS")
        (effects (font (size 0.65 0.65) (thickness 0.15)) (justify left bottom))
    )
    (fp_text value "R_10k_0402" (at 0 1.4 90) (layer "F.Fab") hide
        (effects (font (size 0.7 0.7) (thickness 0.15)) (justify left bottom))
    )
    (fp_text user "License: Apache-2.0" (at -0.95 5.169 90) (layer "F.Fab") hide
        (effects (font (size 0.7 0.7) (thickness 0.15)) (justify left bottom))
    )
    (fp_text user "${REFERENCE}" (at -0.95 3.168 90) (layer "F.Fab") hide
        (effects (font (size 0.7 0.7) (thickness 0.15)) (justify left bottom))
    )
    (fp_text user "Author: Antmicro" (at -0.95 4.169 90) (layer "F.Fab") hide
        (effects (font (size 0.7 0.7) (thickness 0.15)) (justify left bottom))
    )
    (fp_rect (start -0.93 -0.47) (end 0.93 0.47)
      (stroke (width 0.05) (type solid)) (fill none) (layer "F.CrtYd"))
    (fp_rect (start -0.5 -0.25) (end 0.5 0.25)
      (stroke (width 0.15) (type solid)) (fill none) (layer "F.Fab"))
    (pad "1" smd roundrect (at -0.485 0 90) (size 0.59 0.64) (layers "F.Cu" "F.Paste" "F.Mask") (roundrect_rratio 0.25)
      (net 3 "GNDA") (pintype "passive"))
    (pad "2" smd roundrect (at 0.485 0 90) (size 0.59 0.64) (layers "F.Cu" "F.Paste" "F.Mask") (roundrect_rratio 0.25)
      (net 105 "/USER_SW") (pintype "passive"))
  )
	(footprint "sdi-mipi-bridge-footprints:R_0402_1005Metric" (layer "F.Cu")
    (at 139.25 129.765 90)
    (descr "Resistor SMD 0402")
    (tags "resistor SMD 0402")
    (property "Author" "Antmicro")
    (property "License" "Apache-2.0")
    (property "MPN" "CR0402-FX-1002GLF")
    (property "Manufacturer" "Bourns")
    (property "Sheetfile" "sdi-mipi-bridge.kicad_sch")
    (property "Sheetname" "")
    (property "Tolerance" "1%")
    (property "Val" "10k")
    (property "ki_description" "10k resistor in 0402 package with 1% tolerance")
    (attr smd)
    (fp_text reference "R68" (at -5.75 0.4 90) (layer "F.SilkS")
        (effects (font (size 0.65 0.65) (thickness 0.15)) (justify left bottom))
    )
    (fp_text value "R_10k_0402" (at 0 1.4 90) (layer "F.Fab") hide
        (effects (font (size 0.7 0.7) (thickness 0.15)) (justify left bottom))
    )
    (fp_text user "${REFERENCE}" (at -0.95 3.168 90) (layer "F.Fab") hide
        (effects (font (size 0.7 0.7) (thickness 0.15)) (justify left bottom))
    )
    (fp_text user "Author: Antmicro" (at -0.95 4.169 90) (layer "F.Fab") hide
        (effects (font (size 0.7 0.7) (thickness 0.15)) (justify left bottom))
    )
    (fp_text user "License: Apache-2.0" (at -0.95 5.169 90) (layer "F.Fab") hide
        (effects (font (size 0.7 0.7) (thickness 0.15)) (justify left bottom))
    )
    (fp_rect (start -0.93 -0.47) (end 0.93 0.47)
      (stroke (width 0.05) (type solid)) (fill none) (layer "F.CrtYd"))
    (fp_rect (start -0.5 -0.25) (end 0.5 0.25)
      (stroke (width 0.15) (type solid)) (fill none) (layer "F.Fab"))
    (pad "1" smd roundrect (at -0.485 0 90) (size 0.59 0.64) (layers "F.Cu" "F.Paste" "F.Mask") (roundrect_rratio 0.25)
      (net 55 "/SDO_EN_DIS") (pintype "passive"))
    (pad "2" smd roundrect (at 0.485 0 90) (size 0.59 0.64) (layers "F.Cu" "F.Paste" "F.Mask") (roundrect_rratio 0.25)
      (net 76 "IO_VDD") (pintype "passive"))
  )
	(footprint "sdi-mipi-bridge-footprints:R_0402_1005Metric" (layer "F.Cu")
    (at 139.25 131.78 90)
    (descr "Resistor SMD 0402")
    (tags "resistor SMD 0402")
    (property "Author" "Antmicro")
    (property "DNP" "DNP")
    (property "License" "Apache-2.0")
    (property "MPN" "CR0402-FX-1002GLF")
    (property "Manufacturer" "Bourns")
    (property "Sheetfile" "sdi-mipi-bridge.kicad_sch")
    (property "Sheetname" "")
    (property "Tolerance" "1%")
    (property "Val" "10k")
    (property "ki_description" "10k resistor in 0402 package with 1% tolerance")
    (attr exclude_from_pos_files)
    (fp_text reference "R75" (at -5.75 0.4 90) (layer "F.SilkS")
        (effects (font (size 0.65 0.65) (thickness 0.15)) (justify left bottom))
    )
    (fp_text value "R_10k_0402" (at 0 1.4 90) (layer "F.Fab") hide
        (effects (font (size 0.7 0.7) (thickness 0.15)) (justify left bottom))
    )
    (fp_text user "${REFERENCE}" (at -0.95 3.168 90) (layer "F.Fab") hide
        (effects (font (size 0.7 0.7) (thickness 0.15)) (justify left bottom))
    )
    (fp_text user "Author: Antmicro" (at -0.95 4.169 90) (layer "F.Fab") hide
        (effects (font (size 0.7 0.7) (thickness 0.15)) (justify left bottom))
    )
    (fp_text user "License: Apache-2.0" (at -0.95 5.169 90) (layer "F.Fab") hide
        (effects (font (size 0.7 0.7) (thickness 0.15)) (justify left bottom))
    )
    (fp_rect (start -0.93 -0.47) (end 0.93 0.47)
      (stroke (width 0.05) (type solid)) (fill none) (layer "F.CrtYd"))
    (fp_rect (start -0.5 -0.25) (end 0.5 0.25)
      (stroke (width 0.15) (type solid)) (fill none) (layer "F.Fab"))
    (pad "1" smd roundrect (at -0.485 0 90) (size 0.59 0.64) (layers "F.Cu" "F.Paste" "F.Mask") (roundrect_rratio 0.25)
      (net 3 "GNDA") (pintype "passive"))
    (pad "2" smd roundrect (at 0.485 0 90) (size 0.59 0.64) (layers "F.Cu" "F.Paste" "F.Mask") (roundrect_rratio 0.25)
      (net 55 "/SDO_EN_DIS") (pintype "passive"))
  )
	(footprint "sdi-mipi-bridge-footprints:R_0402_1005Metric" (layer "F.Cu")
    (at 141.75 129.75 90)
    (descr "Resistor SMD 0402")
    (tags "resistor SMD 0402")
    (property "Author" "Antmicro")
    (property "License" "Apache-2.0")
    (property "MPN" "CR0402-FX-1002GLF")
    (property "Manufacturer" "Bourns")
    (property "Sheetfile" "sdi-mipi-bridge.kicad_sch")
    (property "Sheetname" "")
    (property "Tolerance" "1%")
    (property "Val" "10k")
    (property "ki_description" "10k resistor in 0402 package with 1% tolerance")
    (attr smd)
    (fp_text reference "R78" (at -5.75 0.4 90) (layer "F.SilkS")
        (effects (font (size 0.65 0.65) (thickness 0.15)) (justify left bottom))
    )
    (fp_text value "R_10k_0402" (at 0 1.4 90) (layer "F.Fab") hide
        (effects (font (size 0.7 0.7) (thickness 0.15)) (justify left bottom))
    )
    (fp_text user "License: Apache-2.0" (at -0.95 5.169 90) (layer "F.Fab") hide
        (effects (font (size 0.7 0.7) (thickness 0.15)) (justify left bottom))
    )
    (fp_text user "${REFERENCE}" (at -0.95 3.168 90) (layer "F.Fab") hide
        (effects (font (size 0.7 0.7) (thickness 0.15)) (justify left bottom))
    )
    (fp_text user "Author: Antmicro" (at -0.95 4.169 90) (layer "F.Fab") hide
        (effects (font (size 0.7 0.7) (thickness 0.15)) (justify left bottom))
    )
    (fp_rect (start -0.93 -0.47) (end 0.93 0.47)
      (stroke (width 0.05) (type solid)) (fill none) (layer "F.CrtYd"))
    (fp_rect (start -0.5 -0.25) (end 0.5 0.25)
      (stroke (width 0.15) (type solid)) (fill none) (layer "F.Fab"))
    (pad "1" smd roundrect (at -0.485 0 90) (size 0.59 0.64) (layers "F.Cu" "F.Paste" "F.Mask") (roundrect_rratio 0.25)
      (net 41 "/IOPROC_EN_~{DIS}") (pintype "passive"))
    (pad "2" smd roundrect (at 0.485 0 90) (size 0.59 0.64) (layers "F.Cu" "F.Paste" "F.Mask") (roundrect_rratio 0.25)
      (net 76 "IO_VDD") (pintype "passive"))
  )
	(footprint "sdi-mipi-bridge-footprints:R_0402_1005Metric" (layer "F.Cu")
    (at 141.75 131.75 90)
    (descr "Resistor SMD 0402")
    (tags "resistor SMD 0402")
    (property "Author" "Antmicro")
    (property "DNP" "DNP")
    (property "License" "Apache-2.0")
    (property "MPN" "CR0402-FX-1002GLF")
    (property "Manufacturer" "Bourns")
    (property "Sheetfile" "sdi-mipi-bridge.kicad_sch")
    (property "Sheetname" "")
    (property "Tolerance" "1%")
    (property "Val" "10k")
    (property "ki_description" "10k resistor in 0402 package with 1% tolerance")
    (attr exclude_from_pos_files)
    (fp_text reference "R79" (at -5.75 0.4 90) (layer "F.SilkS")
        (effects (font (size 0.65 0.65) (thickness 0.15)) (justify left bottom))
    )
    (fp_text value "R_10k_0402" (at 0 1.4 90) (layer "F.Fab") hide
        (effects (font (size 0.7 0.7) (thickness 0.15)) (justify left bottom))
    )
    (fp_text user "${REFERENCE}" (at -0.95 3.168 90) (layer "F.Fab") hide
        (effects (font (size 0.7 0.7) (thickness 0.15)) (justify left bottom))
    )
    (fp_text user "Author: Antmicro" (at -0.95 4.169 90) (layer "F.Fab") hide
        (effects (font (size 0.7 0.7) (thickness 0.15)) (justify left bottom))
    )
    (fp_text user "License: Apache-2.0" (at -0.95 5.169 90) (layer "F.Fab") hide
        (effects (font (size 0.7 0.7) (thickness 0.15)) (justify left bottom))
    )
    (fp_rect (start -0.93 -0.47) (end 0.93 0.47)
      (stroke (width 0.05) (type solid)) (fill none) (layer "F.CrtYd"))
    (fp_rect (start -0.5 -0.25) (end 0.5 0.25)
      (stroke (width 0.15) (type solid)) (fill none) (layer "F.Fab"))
    (pad "1" smd roundrect (at -0.485 0 90) (size 0.59 0.64) (layers "F.Cu" "F.Paste" "F.Mask") (roundrect_rratio 0.25)
      (net 3 "GNDA") (pintype "passive"))
    (pad "2" smd roundrect (at 0.485 0 90) (size 0.59 0.64) (layers "F.Cu" "F.Paste" "F.Mask") (roundrect_rratio 0.25)
      (net 41 "/IOPROC_EN_~{DIS}") (pintype "passive"))
  )
	(footprint "sdi-mipi-bridge-footprints:R_0402_1005Metric" (layer "F.Cu")
    (at 143 129.75 90)
    (descr "Resistor SMD 0402")
    (tags "resistor SMD 0402")
    (property "Author" "Antmicro")
    (property "DNP" "DNP")
    (property "License" "Apache-2.0")
    (property "MPN" "CR0402-FX-1002GLF")
    (property "Manufacturer" "Bourns")
    (property "Sheetfile" "sdi-mipi-bridge.kicad_sch")
    (property "Sheetname" "")
    (property "Tolerance" "1%")
    (property "Val" "10k")
    (property "ki_description" "10k resistor in 0402 package with 1% tolerance")
    (attr exclude_from_pos_files)
    (fp_text reference "R80" (at -5.75 0.4 90) (layer "F.SilkS")
        (effects (font (size 0.65 0.65) (thickness 0.15)) (justify left bottom))
    )
    (fp_text value "R_10k_0402" (at 0 1.4 90) (layer "F.Fab") hide
        (effects (font (size 0.7 0.7) (thickness 0.15)) (justify left bottom))
    )
    (fp_text user "${REFERENCE}" (at -0.95 3.168 90) (layer "F.Fab") hide
        (effects (font (size 0.7 0.7) (thickness 0.15)) (justify left bottom))
    )
    (fp_text user "License: Apache-2.0" (at -0.95 5.169 90) (layer "F.Fab") hide
        (effects (font (size 0.7 0.7) (thickness 0.15)) (justify left bottom))
    )
    (fp_text user "Author: Antmicro" (at -0.95 4.169 90) (layer "F.Fab") hide
        (effects (font (size 0.7 0.7) (thickness 0.15)) (justify left bottom))
    )
    (fp_rect (start -0.93 -0.47) (end 0.93 0.47)
      (stroke (width 0.05) (type solid)) (fill none) (layer "F.CrtYd"))
    (fp_rect (start -0.5 -0.25) (end 0.5 0.25)
      (stroke (width 0.15) (type solid)) (fill none) (layer "F.Fab"))
    (pad "1" smd roundrect (at -0.485 0 90) (size 0.59 0.64) (layers "F.Cu" "F.Paste" "F.Mask") (roundrect_rratio 0.25)
      (net 16 "/20bit_~{10bit}") (pintype "passive"))
    (pad "2" smd roundrect (at 0.485 0 90) (size 0.59 0.64) (layers "F.Cu" "F.Paste" "F.Mask") (roundrect_rratio 0.25)
      (net 76 "IO_VDD") (pintype "passive"))
  )
)
